(kicad_pcb
	(version 20260206)
	(generator "pcbnew")
	(generator_version "10.0")
	(general
		(thickness 1.6)
		(legacy_teardrops no)
	)
	(paper "A4")
	(title_block
		(title "Wiwynn_Tioga_Pass_MB.brd")
		(comment 1 "Tioga Pass / footprints 2112-2118 of 4770")
	)
	(layers
		(0 "F.Cu" signal "TOP")
		(4 "In1.Cu" signal "L2GND")
		(6 "In2.Cu" signal "L3")
		(8 "In3.Cu" signal "L4GND")
		(10 "In4.Cu" signal "L5")
		(12 "In5.Cu" signal "L6GND")
		(14 "In6.Cu" signal "L7VCC")
		(16 "In7.Cu" signal "L8VCC")
		(18 "In8.Cu" signal "L9GND")
		(20 "In9.Cu" signal "L10")
		(22 "In10.Cu" signal "L11GND")
		(24 "In11.Cu" signal "L12")
		(26 "In12.Cu" signal "L13GND")
		(2 "B.Cu" signal "BOTTOM")
		(9 "F.Adhes" user "F.Adhesive")
		(11 "B.Adhes" user "B.Adhesive")
		(13 "F.Paste" user "Package Geometry/Pastemask Top")
		(15 "B.Paste" user "Package Geometry/Pastemask Bottom")
		(5 "F.SilkS" user "Ref Des/Silkscreen Top")
		(7 "B.SilkS" user "Ref Des/Silkscreen Bottom")
		(1 "F.Mask" user "Board Geometry/Soldermask Top")
		(3 "B.Mask" user "Board Geometry/Soldermask Bottom")
		(17 "Dwgs.User" user "User.Drawings")
		(19 "Cmts.User" user "User.Comments")
		(21 "Eco1.User" user "User.Eco1")
		(23 "Eco2.User" user "User.Eco2")
		(25 "Edge.Cuts" user "Board Geometry/Outline")
		(27 "Margin" user)
		(31 "F.CrtYd" user "Package Geometry/Place Bound Top")
		(29 "B.CrtYd" user "Package Geometry/Place Bound Bottom")
		(35 "F.Fab" user "Ref Des/Assembly Top")
		(33 "B.Fab" user "Ref Des/Assembly Bottom")
	)
	(footprint ""
		(layer "F.Cu")
		(at 343.789 -23.45436 90)
		(property "Reference" "C7F9"
			(at 0 0 90)
			(layer "F.SilkS")
			(hide yes)
			(effects
				(font
					(size 1.27 1.27)
				)
			)
		)
		(property "Value" ""
			(at 0 0 90)
			(layer "F.Fab")
			(effects
				(font
					(size 1.27 1.27)
				)
			)
		)
		(duplicate_pad_numbers_are_jumpers no)
		(fp_poly
			(pts
				(xy 0.3048 -0.1016) (xy 0.3048 0.9906) (xy -0.3048 0.9906) (xy -0.3048 -0.1016)
			)
			(stroke
				(width 0)
				(type default)
			)
			(fill no)
			(layer "F.CrtYd")
		)
		(fp_line
			(start 0.3048 -0.1016)
			(end -0.3048 -0.1016)
			(stroke
				(width 0.1)
				(type default)
			)
			(layer "F.Fab")
		)
		(fp_line
			(start -0.3048 -0.1016)
			(end -0.3048 0.9906)
			(stroke
				(width 0.1)
				(type default)
			)
			(layer "F.Fab")
		)
		(fp_line
			(start 0.3048 0.9906)
			(end 0.3048 -0.1016)
			(stroke
				(width 0.1)
				(type default)
			)
			(layer "F.Fab")
		)
		(fp_line
			(start -0.3048 0.9906)
			(end 0.3048 0.9906)
			(stroke
				(width 0.1)
				(type default)
			)
			(layer "F.Fab")
		)
		(pad "1" smd rect
			(at 0 0 90)
			(size 0.508 0.508)
			(layers "F.Cu" "F.Mask" "F.Paste")
			(net "VR_FB_PVPP_ABC")
		)
		(pad "2" smd rect
			(at 0 0.889 90)
			(size 0.508 0.508)
			(layers "F.Cu" "F.Mask" "F.Paste")
			(net "VR_COMP_PVPP_ABC_3")
		)
		(zone
			(layer "F.Cu")
			(hatch none 0.5)
			(connect_pads
				(clearance 0)
			)
			(min_thickness 0.25)
			(keepout
				(tracks allowed)
				(vias not_allowed)
				(pads allowed)
				(copperpour not_allowed)
				(footprints allowed)
			)
			(placement
				(enabled no)
				(sheetname "")
			)
			(fill
				(thermal_gap 0.5)
				(thermal_bridge_width 0.5)
				(island_removal_mode 0)
			)
			(polygon
				(pts
					(xy 344.043 -23.20036) (xy 344.043 -23.70836) (xy 344.424 -23.70836) (xy 344.424 -23.20036)
				)
			)
		)
		(zone
			(layer "F.Cu")
			(hatch none 0.5)
			(connect_pads
				(clearance 0)
			)
			(min_thickness 0.25)
			(keepout
				(tracks not_allowed)
				(vias allowed)
				(pads allowed)
				(copperpour not_allowed)
				(footprints allowed)
			)
			(placement
				(enabled no)
				(sheetname "")
			)
			(fill
				(thermal_gap 0.5)
				(thermal_bridge_width 0.5)
				(island_removal_mode 0)
			)
			(polygon
				(pts
					(xy 344.424 -23.20036) (xy 344.424 -23.70836) (xy 344.043 -23.70836) (xy 344.043 -23.20036)
				)
			)
		)
	)
	(footprint ""
		(layer "F.Cu")
		(at 334.518 -11.3792 180)
		(property "Reference" "C7G28"
			(at 3.02133 6.9088 90)
			(unlocked yes)
			(layer "F.SilkS")
			(effects
				(font
					(size 0.7874 0.5842)
					(thickness 0.1524)
				)
			)
		)
		(property "Value" ""
			(at 0 0 180)
			(layer "F.Fab")
			(effects
				(font
					(size 1.27 1.27)
				)
			)
		)
		(duplicate_pad_numbers_are_jumpers no)
		(fp_line
			(start 2.504948 1.633728)
			(end 1.6002 1.633728)
			(stroke
				(width 0.1524)
				(type default)
			)
			(layer "F.SilkS")
		)
		(fp_line
			(start 2.504948 -1.616456)
			(end 2.504948 1.633728)
			(stroke
				(width 0.1524)
				(type default)
			)
			(layer "F.SilkS")
		)
		(fp_line
			(start 2.286 7.366)
			(end 2.286 1.63195)
			(stroke
				(width 0.1524)
				(type default)
			)
			(layer "F.SilkS")
		)
		(fp_line
			(start 2.286 7.366)
			(end 1.600708 7.366)
			(stroke
				(width 0.1524)
				(type default)
			)
			(layer "F.SilkS")
		)
		(fp_line
			(start 1.6002 -1.616456)
			(end 2.504948 -1.616456)
			(stroke
				(width 0.1524)
				(type default)
			)
			(layer "F.SilkS")
		)
		(fp_line
			(start -1.6002 -1.616456)
			(end -2.563114 -1.616456)
			(stroke
				(width 0.1524)
				(type default)
			)
			(layer "F.SilkS")
		)
		(fp_line
			(start -2.286 7.366)
			(end -1.60147 7.366)
			(stroke
				(width 0.1524)
				(type default)
			)
			(layer "F.SilkS")
		)
		(fp_line
			(start -2.286 7.366)
			(end -2.286 1.632712)
			(stroke
				(width 0.1524)
				(type default)
			)
			(layer "F.SilkS")
		)
		(fp_line
			(start -2.563114 1.633728)
			(end -1.6002 1.633728)
			(stroke
				(width 0.1524)
				(type default)
			)
			(layer "F.SilkS")
		)
		(fp_line
			(start -2.563114 -1.616456)
			(end -2.563114 1.633728)
			(stroke
				(width 0.1524)
				(type default)
			)
			(layer "F.SilkS")
		)
		(fp_rect
			(start 2.286 -0.254)
			(end -2.286 7.366)
			(stroke
				(width 0)
				(type default)
			)
			(fill no)
			(layer "F.CrtYd")
		)
		(fp_line
			(start 2.286 7.366)
			(end -2.286 7.366)
			(stroke
				(width 0.1)
				(type default)
			)
			(layer "F.Fab")
		)
		(fp_line
			(start 2.286 -0.254)
			(end 2.286 7.366)
			(stroke
				(width 0.1)
				(type default)
			)
			(layer "F.Fab")
		)
		(fp_line
			(start -2.286 7.366)
			(end -2.286 -0.254)
			(stroke
				(width 0.1)
				(type default)
			)
			(layer "F.Fab")
		)
		(fp_line
			(start -2.286 -0.254)
			(end 2.286 -0.254)
			(stroke
				(width 0.1)
				(type default)
			)
			(layer "F.Fab")
		)
		(pad "1" smd rect
			(at 0 0 180)
			(size 2.54 3.048)
			(layers "F.Cu" "F.Mask" "F.Paste")
			(net "PVDDQ_ABC")
		)
		(pad "2" smd rect
			(at 0 7.112 180)
			(size 2.54 3.048)
			(layers "F.Cu" "F.Mask" "F.Paste")
			(net "GND")
		)
	)
	(footprint ""
		(layer "F.Cu")
		(at 394.9192 -0.2286)
		(property "Reference" "R8G14"
			(at 0 0 0)
			(layer "F.SilkS")
			(hide yes)
			(effects
				(font
					(size 1.27 1.27)
				)
			)
		)
		(property "Value" ""
			(at 0 0 0)
			(layer "F.Fab")
			(effects
				(font
					(size 1.27 1.27)
				)
			)
		)
		(duplicate_pad_numbers_are_jumpers no)
		(fp_poly
			(pts
				(xy -0.2794 -0.1016) (xy 0.2794 -0.1016) (xy 0.2794 0.9906) (xy -0.2794 0.9906)
			)
			(stroke
				(width 0)
				(type default)
			)
			(fill no)
			(layer "F.CrtYd")
		)
		(fp_line
			(start -0.2794 -0.1016)
			(end -0.2794 0.9906)
			(stroke
				(width 0.1)
				(type default)
			)
			(layer "F.Fab")
		)
		(fp_line
			(start -0.2794 0.9906)
			(end 0.2794 0.9906)
			(stroke
				(width 0.1)
				(type default)
			)
			(layer "F.Fab")
		)
		(fp_line
			(start 0.2794 -0.1016)
			(end -0.2794 -0.1016)
			(stroke
				(width 0.1)
				(type default)
			)
			(layer "F.Fab")
		)
		(fp_line
			(start 0.2794 0.9906)
			(end 0.2794 -0.1016)
			(stroke
				(width 0.1)
				(type default)
			)
			(layer "F.Fab")
		)
		(pad "1" smd rect
			(at 0 0)
			(size 0.508 0.508)
			(layers "F.Cu" "F.Mask" "F.Paste")
			(net "JTAG_BMC_TMS")
		)
		(pad "2" smd rect
			(at 0 0.889)
			(size 0.508 0.508)
			(layers "F.Cu" "F.Mask" "F.Paste")
			(net "JTAG_TMS")
		)
		(zone
			(layer "F.Cu")
			(hatch none 0.5)
			(connect_pads
				(clearance 0)
			)
			(min_thickness 0.25)
			(keepout
				(tracks allowed)
				(vias not_allowed)
				(pads allowed)
				(copperpour not_allowed)
				(footprints allowed)
			)
			(placement
				(enabled no)
				(sheetname "")
			)
			(fill
				(thermal_gap 0.5)
				(thermal_bridge_width 0.5)
				(island_removal_mode 0)
			)
			(polygon
				(pts
					(xy 394.6652 0.0254) (xy 395.1732 0.0254) (xy 395.1732 0.4064) (xy 394.6652 0.4064)
				)
			)
		)
		(zone
			(layer "F.Cu")
			(hatch none 0.5)
			(connect_pads
				(clearance 0)
			)
			(min_thickness 0.25)
			(keepout
				(tracks not_allowed)
				(vias allowed)
				(pads allowed)
				(copperpour not_allowed)
				(footprints allowed)
			)
			(placement
				(enabled no)
				(sheetname "")
			)
			(fill
				(thermal_gap 0.5)
				(thermal_bridge_width 0.5)
				(island_removal_mode 0)
			)
			(polygon
				(pts
					(xy 394.6652 0.4064) (xy 395.1732 0.4064) (xy 395.1732 0.0254) (xy 394.6652 0.0254)
				)
			)
		)
	)
	(footprint ""
		(layer "F.Cu")
		(at 404.03018 -145.085816 -90)
		(property "Reference" "R8A12"
			(at 0 0 270)
			(layer "F.SilkS")
			(hide yes)
			(effects
				(font
					(size 1.27 1.27)
				)
			)
		)
		(property "Value" ""
			(at 0 0 270)
			(layer "F.Fab")
			(effects
				(font
					(size 1.27 1.27)
				)
			)
		)
		(duplicate_pad_numbers_are_jumpers no)
		(fp_poly
			(pts
				(xy -0.4953 -0.2032) (xy 0.4953 -0.2032) (xy 0.4953 1.6002) (xy -0.4953 1.6002)
			)
			(stroke
				(width 0)
				(type default)
			)
			(fill no)
			(layer "F.CrtYd")
		)
		(fp_line
			(start -0.4953 1.6002)
			(end -0.4953 -0.2032)
			(stroke
				(width 0.1)
				(type default)
			)
			(layer "F.Fab")
		)
		(fp_line
			(start 0.4953 1.6002)
			(end -0.4953 1.6002)
			(stroke
				(width 0.1)
				(type default)
			)
			(layer "F.Fab")
		)
		(fp_line
			(start -0.4953 -0.2032)
			(end 0.4953 -0.2032)
			(stroke
				(width 0.1)
				(type default)
			)
			(layer "F.Fab")
		)
		(fp_line
			(start 0.4953 -0.2032)
			(end 0.4953 1.6002)
			(stroke
				(width 0.1)
				(type default)
			)
			(layer "F.Fab")
		)
		(pad "1" smd rect
			(at 0 0 270)
			(size 0.762 0.889)
			(layers "F.Cu" "F.Mask" "F.Paste")
			(net "P1V8_PCH_STBY")
		)
		(pad "2" smd rect
			(at 0 1.397 270)
			(size 0.762 0.889)
			(layers "F.Cu" "F.Mask" "F.Paste")
			(net "GND")
		)
		(zone
			(layer "F.Cu")
			(hatch none 0.5)
			(connect_pads
				(clearance 0)
			)
			(min_thickness 0.25)
			(keepout
				(tracks not_allowed)
				(vias allowed)
				(pads allowed)
				(copperpour not_allowed)
				(footprints allowed)
			)
			(placement
				(enabled no)
				(sheetname "")
			)
			(fill
				(thermal_gap 0.5)
				(thermal_bridge_width 0.5)
				(island_removal_mode 0)
			)
			(polygon
				(pts
					(xy 403.07768 -145.466816) (xy 403.07768 -144.704816) (xy 403.58568 -144.704816) (xy 403.58568 -145.466816)
				)
			)
		)
		(zone
			(layer "F.Cu")
			(hatch none 0.5)
			(connect_pads
				(clearance 0)
			)
			(min_thickness 0.25)
			(keepout
				(tracks allowed)
				(vias not_allowed)
				(pads allowed)
				(copperpour not_allowed)
				(footprints allowed)
			)
			(placement
				(enabled no)
				(sheetname "")
			)
			(fill
				(thermal_gap 0.5)
				(thermal_bridge_width 0.5)
				(island_removal_mode 0)
			)
			(polygon
				(pts
					(xy 403.07768 -144.704816) (xy 403.58568 -144.704816) (xy 403.58568 -145.466816) (xy 403.07768 -145.466816)
				)
			)
		)
	)
	(footprint ""
		(layer "F.Cu")
		(at 29.807916 -22.105366 180)
		(property "Reference" "R1F6"
			(at 0 0 180)
			(layer "F.SilkS")
			(hide yes)
			(effects
				(font
					(size 1.27 1.27)
				)
			)
		)
		(property "Value" ""
			(at 0 0 180)
			(layer "F.Fab")
			(effects
				(font
					(size 1.27 1.27)
				)
			)
		)
		(duplicate_pad_numbers_are_jumpers no)
		(fp_poly
			(pts
				(xy -0.2794 -0.1016) (xy 0.2794 -0.1016) (xy 0.2794 0.9906) (xy -0.2794 0.9906)
			)
			(stroke
				(width 0)
				(type default)
			)
			(fill no)
			(layer "F.CrtYd")
		)
		(fp_line
			(start 0.2794 0.9906)
			(end 0.2794 -0.1016)
			(stroke
				(width 0.1)
				(type default)
			)
			(layer "F.Fab")
		)
		(fp_line
			(start 0.2794 -0.1016)
			(end -0.2794 -0.1016)
			(stroke
				(width 0.1)
				(type default)
			)
			(layer "F.Fab")
		)
		(fp_line
			(start -0.2794 0.9906)
			(end 0.2794 0.9906)
			(stroke
				(width 0.1)
				(type default)
			)
			(layer "F.Fab")
		)
		(fp_line
			(start -0.2794 -0.1016)
			(end -0.2794 0.9906)
			(stroke
				(width 0.1)
				(type default)
			)
			(layer "F.Fab")
		)
		(pad "1" smd rect
			(at 0 0 180)
			(size 0.508 0.508)
			(layers "F.Cu" "F.Mask" "F.Paste")
			(net "M_G_VREF")
		)
		(pad "2" smd rect
			(at 0 0.889 180)
			(size 0.508 0.508)
			(layers "F.Cu" "F.Mask" "F.Paste")
			(net "GND")
		)
		(zone
			(layer "F.Cu")
			(hatch none 0.5)
			(connect_pads
				(clearance 0)
			)
			(min_thickness 0.25)
			(keepout
				(tracks not_allowed)
				(vias allowed)
				(pads allowed)
				(copperpour not_allowed)
				(footprints allowed)
			)
			(placement
				(enabled no)
				(sheetname "")
			)
			(fill
				(thermal_gap 0.5)
				(thermal_bridge_width 0.5)
				(island_removal_mode 0)
			)
			(polygon
				(pts
					(xy 30.061916 -22.740366) (xy 29.553916 -22.740366) (xy 29.553916 -22.359366) (xy 30.061916 -22.359366)
				)
			)
		)
		(zone
			(layer "F.Cu")
			(hatch none 0.5)
			(connect_pads
				(clearance 0)
			)
			(min_thickness 0.25)
			(keepout
				(tracks allowed)
				(vias not_allowed)
				(pads allowed)
				(copperpour not_allowed)
				(footprints allowed)
			)
			(placement
				(enabled no)
				(sheetname "")
			)
			(fill
				(thermal_gap 0.5)
				(thermal_bridge_width 0.5)
				(island_removal_mode 0)
			)
			(polygon
				(pts
					(xy 30.061916 -22.359366) (xy 29.553916 -22.359366) (xy 29.553916 -22.740366) (xy 30.061916 -22.740366)
				)
			)
		)
	)
	(footprint ""
		(layer "F.Cu")
		(at 193.6242 -55.0164)
		(property "Reference" "R4E22"
			(at 0 0 0)
			(layer "F.SilkS")
			(hide yes)
			(effects
				(font
					(size 1.27 1.27)
				)
			)
		)
		(property "Value" ""
			(at 0 0 0)
			(layer "F.Fab")
			(effects
				(font
					(size 1.27 1.27)
				)
			)
		)
		(duplicate_pad_numbers_are_jumpers no)
		(fp_poly
			(pts
				(xy -0.2794 -0.1016) (xy 0.2794 -0.1016) (xy 0.2794 0.9906) (xy -0.2794 0.9906)
			)
			(stroke
				(width 0)
				(type default)
			)
			(fill no)
			(layer "F.CrtYd")
		)
		(fp_line
			(start -0.2794 -0.1016)
			(end -0.2794 0.9906)
			(stroke
				(width 0.1)
				(type default)
			)
			(layer "F.Fab")
		)
		(fp_line
			(start -0.2794 0.9906)
			(end 0.2794 0.9906)
			(stroke
				(width 0.1)
				(type default)
			)
			(layer "F.Fab")
		)
		(fp_line
			(start 0.2794 -0.1016)
			(end -0.2794 -0.1016)
			(stroke
				(width 0.1)
				(type default)
			)
			(layer "F.Fab")
		)
		(fp_line
			(start 0.2794 0.9906)
			(end 0.2794 -0.1016)
			(stroke
				(width 0.1)
				(type default)
			)
			(layer "F.Fab")
		)
		(pad "1" smd rect
			(at 0 0)
			(size 0.508 0.508)
			(layers "F.Cu" "F.Mask" "F.Paste")
			(net "VR_PVCCIN_CPU0_PH1_OCSET")
		)
		(pad "2" smd rect
			(at 0 0.889)
			(size 0.508 0.508)
			(layers "F.Cu" "F.Mask" "F.Paste")
			(net "GND")
		)
		(zone
			(layer "F.Cu")
			(hatch none 0.5)
			(connect_pads
				(clearance 0)
			)
			(min_thickness 0.25)
			(keepout
				(tracks allowed)
				(vias not_allowed)
				(pads allowed)
				(copperpour not_allowed)
				(footprints allowed)
			)
			(placement
				(enabled no)
				(sheetname "")
			)
			(fill
				(thermal_gap 0.5)
				(thermal_bridge_width 0.5)
				(island_removal_mode 0)
			)
			(polygon
				(pts
					(xy 193.3702 -54.7624) (xy 193.8782 -54.7624) (xy 193.8782 -54.3814) (xy 193.3702 -54.3814)
				)
			)
		)
		(zone
			(layer "F.Cu")
			(hatch none 0.5)
			(connect_pads
				(clearance 0)
			)
			(min_thickness 0.25)
			(keepout
				(tracks not_allowed)
				(vias allowed)
				(pads allowed)
				(copperpour not_allowed)
				(footprints allowed)
			)
			(placement
				(enabled no)
				(sheetname "")
			)
			(fill
				(thermal_gap 0.5)
				(thermal_bridge_width 0.5)
				(island_removal_mode 0)
			)
			(polygon
				(pts
					(xy 193.3702 -54.3814) (xy 193.8782 -54.3814) (xy 193.8782 -54.7624) (xy 193.3702 -54.7624)
				)
			)
		)
	)
	(footprint ""
		(layer "F.Cu")
		(at 436.547006 -43.556174 180)
		(property "Reference" "R25W45"
			(at 0 0 180)
			(layer "F.SilkS")
			(hide yes)
			(effects
				(font
					(size 1.27 1.27)
				)
			)
		)
		(property "Value" "*"
			(at 0.064008 -4.108196 180)
			(unlocked yes)
			(layer "F.Fab")
			(hide yes)
			(effects
				(font
					(size 1.27 1.016)
					(thickness 0.1524)
				)
			)
		)
		(property "Device Type" "120R2F-GP_RCL_GP-120R2F-GP,64.A"
			(at 0.064008 -5.632196 180)
			(unlocked yes)
			(layer "F.Fab")
			(hide yes)
			(effects
				(font
					(size 1.27 1.016)
					(thickness 0.1524)
				)
			)
		)
		(duplicate_pad_numbers_are_jumpers no)
		(fp_line
			(start 0.508 -0.9398)
			(end -0.508 -0.9398)
			(stroke
				(width 0.1524)
				(type default)
			)
			(layer "F.SilkS")
		)
		(fp_line
			(start -0.508 -0.9398)
			(end -0.508 0.9398)
			(stroke
				(width 0.1524)
				(type default)
			)
			(layer "F.SilkS")
		)
		(fp_rect
			(start -0.508 0.9398)
			(end 0.508 -0.9398)
			(stroke
				(width 0)
				(type default)
			)
			(fill no)
			(layer "F.CrtYd")
		)
		(fp_rect
			(start -0.508 0.9398)
			(end 0.508 -0.9398)
			(stroke
				(width 0)
				(type default)
			)
			(fill no)
			(layer "F.Fab")
		)
		(pad "1" smd custom
			(at 0 -0.4445 180)
			(size 0.1397 0.1397)
			(layers "F.Cu" "F.Mask" "F.Paste")
			(net "BMC_M_A7")
			(options
				(clearance outline)
				(anchor circle)
			)
			(primitives
				(gr_poly
					(pts
						(arc
							(start -0.1778 -0.2794)
							(mid -0.249642 -0.249642)
							(end -0.2794 -0.1778)
						)
						(arc
							(start -0.2794 0.1778)
							(mid -0.249642 0.249642)
							(end -0.1778 0.2794)
						)
						(arc
							(start 0.1778 0.2794)
							(mid 0.249642 0.249642)
							(end 0.2794 0.1778)
						)
						(arc
							(start 0.2794 -0.1778)
							(mid 0.249642 -0.249642)
							(end 0.1778 -0.2794)
						)
					)
					(width 0)
					(fill yes)
				)
			)
		)
		(pad "2" smd custom
			(at 0 0.4445 180)
			(size 0.1397 0.1397)
			(layers "F.Cu" "F.Mask" "F.Paste")
			(net "P1V2_AUX_BMC")
			(options
				(clearance outline)
				(anchor circle)
			)
			(primitives
				(gr_poly
					(pts
						(arc
							(start -0.1778 -0.2794)
							(mid -0.249642 -0.249642)
							(end -0.2794 -0.1778)
						)
						(arc
							(start -0.2794 0.1778)
							(mid -0.249642 0.249642)
							(end -0.1778 0.2794)
						)
						(arc
							(start 0.1778 0.2794)
							(mid 0.249642 0.249642)
							(end 0.2794 0.1778)
						)
						(arc
							(start 0.2794 -0.1778)
							(mid 0.249642 -0.249642)
							(end 0.1778 -0.2794)
						)
					)
					(width 0)
					(fill yes)
				)
			)
		)
	)
)
